# T6G (Grand Teton) — schematic netlist excerpt (pin names and nets, part order shuffled) for the footprints in the layout excerpt that follows; sources: Cadence DE-HDL packaged netlist, KiCad conversion of 04192023_DAF0TMB3IC0_F0TG_MB_C_brd_V02_OCP.brd

C7510  Q_CAP  0.1UF 10V 10% X7S  pkg C0201  page 278 : A = P1V8_CPU0_RT_1D ; B = GND
PC368  Q_CAP  470PF 50V 10% X7R  pkg 0402  page 217 : A = PVDDCR_CPU1_P1_TEMP0 ; B = GND
C1102  Q_CAP  0.1UF 25V 10% X7R  pkg 0402  page 77 : A = PVDD18_S5_P0 ; B = GND

(kicad_pcb
	(version 20260206)
	(generator "pcbnew")
	(generator_version "10.0")
	(general
		(thickness 1.6)
		(legacy_teardrops no)
	)
	(paper "A4")
	(title_block
		(title "04192023_DAF0TMB3IC0_F0TG_MB_C_brd_V02_OCP.brd")
		(comment 1 "Grand Teton / footprints 1159-1161 of 8354")
	)
	(layers
		(0 "F.Cu" signal "TOP")
		(4 "In1.Cu" signal "GND")
		(6 "In2.Cu" signal "IN1")
		(8 "In3.Cu" signal "GND1")
		(10 "In4.Cu" signal "IN2")
		(12 "In5.Cu" signal "GND2")
		(14 "In6.Cu" signal "IN3")
		(16 "In7.Cu" signal "GND3")
		(18 "In8.Cu" signal "VCC")
		(20 "In9.Cu" signal "VCC1")
		(22 "In10.Cu" signal "GND4")
		(24 "In11.Cu" signal "IN4")
		(26 "In12.Cu" signal "GND5")
		(28 "In13.Cu" signal "IN5")
		(30 "In14.Cu" signal "GND6")
		(32 "In15.Cu" signal "IN6")
		(34 "In16.Cu" signal "GND7")
		(2 "B.Cu" signal "BOTTOM")
		(9 "F.Adhes" user "F.Adhesive")
		(11 "B.Adhes" user "B.Adhesive")
		(13 "F.Paste" user "Package Geometry/Pastemask Top")
		(15 "B.Paste" user "Package Geometry/Pastemask Bottom")
		(5 "F.SilkS" user "Ref Des/Silkscreen Top")
		(7 "B.SilkS" user "Ref Des/Silkscreen Bottom")
		(1 "F.Mask" user "Board Geometry/Soldermask Top")
		(3 "B.Mask" user "Board Geometry/Soldermask Bottom")
		(17 "Dwgs.User" user "User.Drawings")
		(19 "Cmts.User" user "User.Comments")
		(21 "Eco1.User" user "User.Eco1")
		(23 "Eco2.User" user "User.Eco2")
		(25 "Edge.Cuts" user "Board Geometry/Outline")
		(27 "Margin" user)
		(31 "F.CrtYd" user "Package Geometry/Place Bound Top")
		(29 "B.CrtYd" user "Package Geometry/Place Bound Bottom")
		(35 "F.Fab" user "Ref Des/Assembly Top")
		(33 "B.Fab" user "Ref Des/Assembly Bottom")
	)
	(footprint ""
		(layer "F.Cu")
		(at 256.592324 -129.617216)
		(property "Reference" "C1102"
			(at 0 0 0)
			(layer "F.SilkS")
			(hide yes)
			(effects
				(font
					(size 1.27 1.27)
				)
			)
		)
		(property "Value" ""
			(at 0 0 0)
			(layer "F.Fab")
			(effects
				(font
					(size 1.27 1.27)
				)
			)
		)
		(duplicate_pad_numbers_are_jumpers no)
		(fp_line
			(start -0.7874 -0.4064)
			(end 0.7874 -0.4064)
			(stroke
				(width 0.1524)
				(type default)
			)
			(layer "F.SilkS")
		)
		(fp_line
			(start -0.7874 0.4064)
			(end -0.7874 -0.4064)
			(stroke
				(width 0.1524)
				(type default)
			)
			(layer "F.SilkS")
		)
		(fp_line
			(start 0.7874 -0.4064)
			(end 0.7874 0.4064)
			(stroke
				(width 0.1524)
				(type default)
			)
			(layer "F.SilkS")
		)
		(fp_line
			(start 0.7874 0.4064)
			(end -0.7874 0.4064)
			(stroke
				(width 0.1524)
				(type default)
			)
			(layer "F.SilkS")
		)
		(fp_line
			(start -0.67945 -0.305054)
			(end -0.12065 -0.305054)
			(stroke
				(width 0.1)
				(type default)
			)
			(layer "F.Fab")
		)
		(fp_line
			(start -0.67945 0.3048)
			(end -0.67945 -0.305054)
			(stroke
				(width 0.1)
				(type default)
			)
			(layer "F.Fab")
		)
		(fp_line
			(start -0.12065 -0.305054)
			(end -0.12065 -0.2794)
			(stroke
				(width 0.1)
				(type default)
			)
			(layer "F.Fab")
		)
		(fp_line
			(start -0.12065 -0.2794)
			(end 0.12065 -0.2794)
			(stroke
				(width 0.1)
				(type default)
			)
			(layer "F.Fab")
		)
		(fp_line
			(start -0.12065 0.2794)
			(end -0.12065 0.3048)
			(stroke
				(width 0.1)
				(type default)
			)
			(layer "F.Fab")
		)
		(fp_line
			(start -0.12065 0.3048)
			(end -0.67945 0.3048)
			(stroke
				(width 0.1)
				(type default)
			)
			(layer "F.Fab")
		)
		(fp_line
			(start 0.120396 0.2794)
			(end -0.12065 0.2794)
			(stroke
				(width 0.1)
				(type default)
			)
			(layer "F.Fab")
		)
		(fp_line
			(start 0.120396 0.3048)
			(end 0.120396 0.2794)
			(stroke
				(width 0.1)
				(type default)
			)
			(layer "F.Fab")
		)
		(fp_line
			(start 0.12065 -0.3048)
			(end 0.67945 -0.3048)
			(stroke
				(width 0.1)
				(type default)
			)
			(layer "F.Fab")
		)
		(fp_line
			(start 0.12065 -0.2794)
			(end 0.12065 -0.3048)
			(stroke
				(width 0.1)
				(type default)
			)
			(layer "F.Fab")
		)
		(fp_line
			(start 0.67945 -0.3048)
			(end 0.67945 0.3048)
			(stroke
				(width 0.1)
				(type default)
			)
			(layer "F.Fab")
		)
		(fp_line
			(start 0.67945 0.3048)
			(end 0.120396 0.3048)
			(stroke
				(width 0.1)
				(type default)
			)
			(layer "F.Fab")
		)
		(pad "1" smd circle
			(at -0.40005 0)
			(size 0 0)
			(layers "F.Cu" "F.Mask" "F.Paste")
			(net "PVDD18_S5_P0")
		)
		(pad "2" smd circle
			(at 0.40005 0)
			(size 0 0)
			(layers "F.Cu" "F.Mask" "F.Paste")
			(net "GND")
		)
	)
	(footprint ""
		(layer "F.Cu")
		(at 37.211 -364.109)
		(property "Reference" "PC368"
			(at 0 0 0)
			(layer "F.SilkS")
			(hide yes)
			(effects
				(font
					(size 1.27 1.27)
				)
			)
		)
		(property "Value" ""
			(at 0 0 0)
			(layer "F.Fab")
			(effects
				(font
					(size 1.27 1.27)
				)
			)
		)
		(duplicate_pad_numbers_are_jumpers no)
		(fp_line
			(start -0.7874 -0.4064)
			(end 0.7874 -0.4064)
			(stroke
				(width 0.1524)
				(type default)
			)
			(layer "F.SilkS")
		)
		(fp_line
			(start -0.7874 0.4064)
			(end -0.7874 -0.4064)
			(stroke
				(width 0.1524)
				(type default)
			)
			(layer "F.SilkS")
		)
		(fp_line
			(start 0.7874 -0.4064)
			(end 0.7874 0.4064)
			(stroke
				(width 0.1524)
				(type default)
			)
			(layer "F.SilkS")
		)
		(fp_line
			(start 0.7874 0.4064)
			(end -0.7874 0.4064)
			(stroke
				(width 0.1524)
				(type default)
			)
			(layer "F.SilkS")
		)
		(fp_line
			(start -0.67945 -0.305054)
			(end -0.12065 -0.305054)
			(stroke
				(width 0.1)
				(type default)
			)
			(layer "F.Fab")
		)
		(fp_line
			(start -0.67945 0.3048)
			(end -0.67945 -0.305054)
			(stroke
				(width 0.1)
				(type default)
			)
			(layer "F.Fab")
		)
		(fp_line
			(start -0.12065 -0.305054)
			(end -0.12065 -0.2794)
			(stroke
				(width 0.1)
				(type default)
			)
			(layer "F.Fab")
		)
		(fp_line
			(start -0.12065 -0.2794)
			(end 0.12065 -0.2794)
			(stroke
				(width 0.1)
				(type default)
			)
			(layer "F.Fab")
		)
		(fp_line
			(start -0.12065 0.2794)
			(end -0.12065 0.3048)
			(stroke
				(width 0.1)
				(type default)
			)
			(layer "F.Fab")
		)
		(fp_line
			(start -0.12065 0.3048)
			(end -0.67945 0.3048)
			(stroke
				(width 0.1)
				(type default)
			)
			(layer "F.Fab")
		)
		(fp_line
			(start 0.120396 0.2794)
			(end -0.12065 0.2794)
			(stroke
				(width 0.1)
				(type default)
			)
			(layer "F.Fab")
		)
		(fp_line
			(start 0.120396 0.3048)
			(end 0.120396 0.2794)
			(stroke
				(width 0.1)
				(type default)
			)
			(layer "F.Fab")
		)
		(fp_line
			(start 0.12065 -0.3048)
			(end 0.67945 -0.3048)
			(stroke
				(width 0.1)
				(type default)
			)
			(layer "F.Fab")
		)
		(fp_line
			(start 0.12065 -0.2794)
			(end 0.12065 -0.3048)
			(stroke
				(width 0.1)
				(type default)
			)
			(layer "F.Fab")
		)
		(fp_line
			(start 0.67945 -0.3048)
			(end 0.67945 0.3048)
			(stroke
				(width 0.1)
				(type default)
			)
			(layer "F.Fab")
		)
		(fp_line
			(start 0.67945 0.3048)
			(end 0.120396 0.3048)
			(stroke
				(width 0.1)
				(type default)
			)
			(layer "F.Fab")
		)
		(pad "1" smd circle
			(at -0.40005 0)
			(size 0 0)
			(layers "F.Cu" "F.Mask" "F.Paste")
			(net "PVDDCR_CPU1_P1_TEMP0")
		)
		(pad "2" smd circle
			(at 0.40005 0)
			(size 0 0)
			(layers "F.Cu" "F.Mask" "F.Paste")
			(net "GND")
		)
	)
	(footprint ""
		(layer "F.Cu")
		(at 302.344836 -422.967404 90)
		(property "Reference" "C7510"
			(at 0 0 90)
			(layer "F.SilkS")
			(hide yes)
			(effects
				(font
					(size 1.27 1.27)
				)
			)
		)
		(property "Value" ""
			(at 0 0 90)
			(layer "F.Fab")
			(effects
				(font
					(size 1.27 1.27)
				)
			)
		)
		(duplicate_pad_numbers_are_jumpers no)
		(fp_line
			(start 0.299974 -0.150114)
			(end 0.299974 0.150114)
			(stroke
				(width 0.1)
				(type default)
			)
			(layer "F.Fab")
		)
		(fp_line
			(start -0.299974 -0.150114)
			(end 0.299974 -0.150114)
			(stroke
				(width 0.1)
				(type default)
			)
			(layer "F.Fab")
		)
		(fp_line
			(start 0.299974 0.150114)
			(end -0.299974 0.150114)
			(stroke
				(width 0.1)
				(type default)
			)
			(layer "F.Fab")
		)
		(fp_line
			(start -0.299974 0.150114)
			(end -0.299974 -0.150114)
			(stroke
				(width 0.1)
				(type default)
			)
			(layer "F.Fab")
		)
		(pad "1" smd rect
			(at -0.2667 0 90)
			(size 0.3048 0.381)
			(layers "F.Cu" "F.Mask" "F.Paste")
			(net "P1V8_CPU0_RT_1D")
		)
		(pad "2" smd rect
			(at 0.2667 0 90)
			(size 0.3048 0.381)
			(layers "F.Cu" "F.Mask" "F.Paste")
			(net "GND")
		)
	)
)
